# T6G (Grand Teton) — schematic netlist excerpt (pin names and nets, part order shuffled) for the footprints in the layout excerpt that follows; sources: Cadence DE-HDL packaged netlist, KiCad conversion of 04192023_DAF0TMB3IC0_F0TG_MB_C_brd_V02_OCP.brd

R2261  Q_RES  33.2 1% CHIP  pkg 0402LF  page 81 : A = FM_SWB_PWR_EN_R ; B = FM_SWB_PWR_EN
R2944  Q_RES  33.2 1% CHIP  pkg 0402LF  page 241 : A = FM_GPU_HSC_EN_BUF_R ; B = FM_GPU_HSC_EN_BUF
C1565  Q_CAP_DIFFBUS  DIFF BUS_0.22UF 6.3V 20% X6S  pkg C0201  page 65 : \1\ = P5E_CPU0_G3_TX_C_DP<7> ; \2\ = P5E_CPU0_G3_TX_DP<7>

(kicad_pcb
	(version 20260206)
	(generator "pcbnew")
	(generator_version "10.0")
	(general
		(thickness 1.6)
		(legacy_teardrops no)
	)
	(paper "A4")
	(title_block
		(title "04192023_DAF0TMB3IC0_F0TG_MB_C_brd_V02_OCP.brd")
		(comment 1 "Grand Teton / footprints 161-163 of 8354")
	)
	(layers
		(0 "F.Cu" signal "TOP")
		(4 "In1.Cu" signal "GND")
		(6 "In2.Cu" signal "IN1")
		(8 "In3.Cu" signal "GND1")
		(10 "In4.Cu" signal "IN2")
		(12 "In5.Cu" signal "GND2")
		(14 "In6.Cu" signal "IN3")
		(16 "In7.Cu" signal "GND3")
		(18 "In8.Cu" signal "VCC")
		(20 "In9.Cu" signal "VCC1")
		(22 "In10.Cu" signal "GND4")
		(24 "In11.Cu" signal "IN4")
		(26 "In12.Cu" signal "GND5")
		(28 "In13.Cu" signal "IN5")
		(30 "In14.Cu" signal "GND6")
		(32 "In15.Cu" signal "IN6")
		(34 "In16.Cu" signal "GND7")
		(2 "B.Cu" signal "BOTTOM")
		(9 "F.Adhes" user "F.Adhesive")
		(11 "B.Adhes" user "B.Adhesive")
		(13 "F.Paste" user "Package Geometry/Pastemask Top")
		(15 "B.Paste" user "Package Geometry/Pastemask Bottom")
		(5 "F.SilkS" user "Ref Des/Silkscreen Top")
		(7 "B.SilkS" user "Ref Des/Silkscreen Bottom")
		(1 "F.Mask" user "Board Geometry/Soldermask Top")
		(3 "B.Mask" user "Board Geometry/Soldermask Bottom")
		(17 "Dwgs.User" user "User.Drawings")
		(19 "Cmts.User" user "User.Comments")
		(21 "Eco1.User" user "User.Eco1")
		(23 "Eco2.User" user "User.Eco2")
		(25 "Edge.Cuts" user "Board Geometry/Outline")
		(27 "Margin" user)
		(31 "F.CrtYd" user "Package Geometry/Place Bound Top")
		(29 "B.CrtYd" user "Package Geometry/Place Bound Bottom")
		(35 "F.Fab" user "Ref Des/Assembly Top")
		(33 "B.Fab" user "Ref Des/Assembly Bottom")
	)
	(footprint ""
		(layer "F.Cu")
		(at 413.273748 -16.100298 90)
		(property "Reference" "C1565"
			(at 0 0 90)
			(layer "F.SilkS")
			(hide yes)
			(effects
				(font
					(size 1.27 1.27)
				)
			)
		)
		(property "Value" ""
			(at 0 0 90)
			(layer "F.Fab")
			(effects
				(font
					(size 1.27 1.27)
				)
			)
		)
		(duplicate_pad_numbers_are_jumpers no)
		(fp_line
			(start 0.299974 -0.150114)
			(end 0.299974 0.150114)
			(stroke
				(width 0.1)
				(type default)
			)
			(layer "F.Fab")
		)
		(fp_line
			(start -0.299974 -0.150114)
			(end 0.299974 -0.150114)
			(stroke
				(width 0.1)
				(type default)
			)
			(layer "F.Fab")
		)
		(fp_line
			(start 0.299974 0.150114)
			(end -0.299974 0.150114)
			(stroke
				(width 0.1)
				(type default)
			)
			(layer "F.Fab")
		)
		(fp_line
			(start -0.299974 0.150114)
			(end -0.299974 -0.150114)
			(stroke
				(width 0.1)
				(type default)
			)
			(layer "F.Fab")
		)
		(pad "1" smd rect
			(at -0.2667 0 90)
			(size 0.3048 0.381)
			(layers "F.Cu" "F.Mask" "F.Paste")
			(net "P5E_CPU0_G3_TX_C_DP<7>")
		)
		(pad "2" smd rect
			(at 0.2667 0 90)
			(size 0.3048 0.381)
			(layers "F.Cu" "F.Mask" "F.Paste")
			(net "P5E_CPU0_G3_TX_DP<7>")
		)
	)
	(footprint ""
		(layer "F.Cu")
		(at 195.961 -100.294948 90)
		(property "Reference" "R2261"
			(at 0 0 90)
			(layer "F.SilkS")
			(hide yes)
			(effects
				(font
					(size 1.27 1.27)
				)
			)
		)
		(property "Value" ""
			(at 0 0 90)
			(layer "F.Fab")
			(effects
				(font
					(size 1.27 1.27)
				)
			)
		)
		(duplicate_pad_numbers_are_jumpers no)
		(fp_line
			(start 0.7874 -0.4064)
			(end 0.7874 0.4064)
			(stroke
				(width 0.1524)
				(type default)
			)
			(layer "F.SilkS")
		)
		(fp_line
			(start -0.7874 -0.4064)
			(end 0.7874 -0.4064)
			(stroke
				(width 0.1524)
				(type default)
			)
			(layer "F.SilkS")
		)
		(fp_line
			(start 0.7874 0.4064)
			(end -0.7874 0.4064)
			(stroke
				(width 0.1524)
				(type default)
			)
			(layer "F.SilkS")
		)
		(fp_line
			(start -0.7874 0.4064)
			(end -0.7874 -0.4064)
			(stroke
				(width 0.1524)
				(type default)
			)
			(layer "F.SilkS")
		)
		(fp_line
			(start -0.12065 -0.305054)
			(end -0.12065 -0.2794)
			(stroke
				(width 0.1)
				(type default)
			)
			(layer "F.Fab")
		)
		(fp_line
			(start -0.67945 -0.305054)
			(end -0.12065 -0.305054)
			(stroke
				(width 0.1)
				(type default)
			)
			(layer "F.Fab")
		)
		(fp_line
			(start 0.67945 -0.3048)
			(end 0.67945 0.3048)
			(stroke
				(width 0.1)
				(type default)
			)
			(layer "F.Fab")
		)
		(fp_line
			(start 0.12065 -0.3048)
			(end 0.67945 -0.3048)
			(stroke
				(width 0.1)
				(type default)
			)
			(layer "F.Fab")
		)
		(fp_line
			(start 0.12065 -0.2794)
			(end 0.12065 -0.3048)
			(stroke
				(width 0.1)
				(type default)
			)
			(layer "F.Fab")
		)
		(fp_line
			(start -0.12065 -0.2794)
			(end 0.12065 -0.2794)
			(stroke
				(width 0.1)
				(type default)
			)
			(layer "F.Fab")
		)
		(fp_line
			(start 0.120396 0.2794)
			(end -0.12065 0.2794)
			(stroke
				(width 0.1)
				(type default)
			)
			(layer "F.Fab")
		)
		(fp_line
			(start -0.12065 0.2794)
			(end -0.12065 0.3048)
			(stroke
				(width 0.1)
				(type default)
			)
			(layer "F.Fab")
		)
		(fp_line
			(start 0.67945 0.3048)
			(end 0.120396 0.3048)
			(stroke
				(width 0.1)
				(type default)
			)
			(layer "F.Fab")
		)
		(fp_line
			(start 0.120396 0.3048)
			(end 0.120396 0.2794)
			(stroke
				(width 0.1)
				(type default)
			)
			(layer "F.Fab")
		)
		(fp_line
			(start -0.12065 0.3048)
			(end -0.67945 0.3048)
			(stroke
				(width 0.1)
				(type default)
			)
			(layer "F.Fab")
		)
		(fp_line
			(start -0.67945 0.3048)
			(end -0.67945 -0.305054)
			(stroke
				(width 0.1)
				(type default)
			)
			(layer "F.Fab")
		)
		(pad "1" smd circle
			(at -0.40005 0 90)
			(size 0 0)
			(layers "F.Cu" "F.Mask" "F.Paste")
			(net "FM_SWB_PWR_EN_R")
		)
		(pad "2" smd circle
			(at 0.40005 0 90)
			(size 0 0)
			(layers "F.Cu" "F.Mask" "F.Paste")
			(net "FM_SWB_PWR_EN")
		)
	)
	(footprint ""
		(layer "F.Cu")
		(at 191.52362 -422.804082 90)
		(property "Reference" "R2944"
			(at 0 0 90)
			(layer "F.SilkS")
			(hide yes)
			(effects
				(font
					(size 1.27 1.27)
				)
			)
		)
		(property "Value" ""
			(at 0 0 90)
			(layer "F.Fab")
			(effects
				(font
					(size 1.27 1.27)
				)
			)
		)
		(duplicate_pad_numbers_are_jumpers no)
		(fp_line
			(start 0.7874 -0.4064)
			(end 0.7874 0.4064)
			(stroke
				(width 0.1524)
				(type default)
			)
			(layer "F.SilkS")
		)
		(fp_line
			(start -0.7874 -0.4064)
			(end 0.7874 -0.4064)
			(stroke
				(width 0.1524)
				(type default)
			)
			(layer "F.SilkS")
		)
		(fp_line
			(start 0.7874 0.4064)
			(end -0.7874 0.4064)
			(stroke
				(width 0.1524)
				(type default)
			)
			(layer "F.SilkS")
		)
		(fp_line
			(start -0.7874 0.4064)
			(end -0.7874 -0.4064)
			(stroke
				(width 0.1524)
				(type default)
			)
			(layer "F.SilkS")
		)
		(fp_line
			(start -0.12065 -0.305054)
			(end -0.12065 -0.2794)
			(stroke
				(width 0.1)
				(type default)
			)
			(layer "F.Fab")
		)
		(fp_line
			(start -0.67945 -0.305054)
			(end -0.12065 -0.305054)
			(stroke
				(width 0.1)
				(type default)
			)
			(layer "F.Fab")
		)
		(fp_line
			(start 0.67945 -0.3048)
			(end 0.67945 0.3048)
			(stroke
				(width 0.1)
				(type default)
			)
			(layer "F.Fab")
		)
		(fp_line
			(start 0.12065 -0.3048)
			(end 0.67945 -0.3048)
			(stroke
				(width 0.1)
				(type default)
			)
			(layer "F.Fab")
		)
		(fp_line
			(start 0.12065 -0.2794)
			(end 0.12065 -0.3048)
			(stroke
				(width 0.1)
				(type default)
			)
			(layer "F.Fab")
		)
		(fp_line
			(start -0.12065 -0.2794)
			(end 0.12065 -0.2794)
			(stroke
				(width 0.1)
				(type default)
			)
			(layer "F.Fab")
		)
		(fp_line
			(start 0.120396 0.2794)
			(end -0.12065 0.2794)
			(stroke
				(width 0.1)
				(type default)
			)
			(layer "F.Fab")
		)
		(fp_line
			(start -0.12065 0.2794)
			(end -0.12065 0.3048)
			(stroke
				(width 0.1)
				(type default)
			)
			(layer "F.Fab")
		)
		(fp_line
			(start 0.67945 0.3048)
			(end 0.120396 0.3048)
			(stroke
				(width 0.1)
				(type default)
			)
			(layer "F.Fab")
		)
		(fp_line
			(start 0.120396 0.3048)
			(end 0.120396 0.2794)
			(stroke
				(width 0.1)
				(type default)
			)
			(layer "F.Fab")
		)
		(fp_line
			(start -0.12065 0.3048)
			(end -0.67945 0.3048)
			(stroke
				(width 0.1)
				(type default)
			)
			(layer "F.Fab")
		)
		(fp_line
			(start -0.67945 0.3048)
			(end -0.67945 -0.305054)
			(stroke
				(width 0.1)
				(type default)
			)
			(layer "F.Fab")
		)
		(pad "1" smd circle
			(at -0.40005 0 90)
			(size 0 0)
			(layers "F.Cu" "F.Mask" "F.Paste")
			(net "FM_GPU_HSC_EN_BUF_R")
		)
		(pad "2" smd circle
			(at 0.40005 0 90)
			(size 0 0)
			(layers "F.Cu" "F.Mask" "F.Paste")
			(net "FM_GPU_HSC_EN_BUF")
		)
	)
)
